(kicad_pcb
	(version 20260206)
	(generator "pcbnew")
	(generator_version "10.0")
	(general
		(thickness 1.6)
		(legacy_teardrops no)
	)
	(paper "A4")
	(title_block
		(title "Wiwynn_Tioga_Pass_MB.brd")
		(comment 1 "Tioga Pass / footprint 2254 of 4770 (U5D1), pads 1122-1228 of 3647")
	)
	(layers
		(0 "F.Cu" signal "TOP")
		(4 "In1.Cu" signal "L2GND")
		(6 "In2.Cu" signal "L3")
		(8 "In3.Cu" signal "L4GND")
		(10 "In4.Cu" signal "L5")
		(12 "In5.Cu" signal "L6GND")
		(14 "In6.Cu" signal "L7VCC")
		(16 "In7.Cu" signal "L8VCC")
		(18 "In8.Cu" signal "L9GND")
		(20 "In9.Cu" signal "L10")
		(22 "In10.Cu" signal "L11GND")
		(24 "In11.Cu" signal "L12")
		(26 "In12.Cu" signal "L13GND")
		(2 "B.Cu" signal "BOTTOM")
		(9 "F.Adhes" user "F.Adhesive")
		(11 "B.Adhes" user "B.Adhesive")
		(13 "F.Paste" user "Package Geometry/Pastemask Top")
		(15 "B.Paste" user "Package Geometry/Pastemask Bottom")
		(5 "F.SilkS" user "Ref Des/Silkscreen Top")
		(7 "B.SilkS" user "Ref Des/Silkscreen Bottom")
		(1 "F.Mask" user "Board Geometry/Soldermask Top")
		(3 "B.Mask" user "Board Geometry/Soldermask Bottom")
		(17 "Dwgs.User" user "User.Drawings")
		(19 "Cmts.User" user "User.Comments")
		(21 "Eco1.User" user "User.Eco1")
		(23 "Eco2.User" user "User.Eco2")
		(25 "Edge.Cuts" user "Board Geometry/Outline")
		(27 "Margin" user)
		(31 "F.CrtYd" user "Package Geometry/Place Bound Top")
		(29 "B.CrtYd" user "Package Geometry/Place Bound Bottom")
		(35 "F.Fab" user "Ref Des/Assembly Top")
		(33 "B.Fab" user "Ref Des/Assembly Bottom")
	)
	(footprint ""
		(layer "F.Cu")
		(at 270.000222 -76.550012 180)
		(property "Reference" "U5D1"
			(at 19.124422 31.601918 0)
			(unlocked yes)
			(layer "F.SilkS")
			(effects
				(font
					(size 0.7874 0.5842)
					(thickness 0.1524)
				)
			)
		)
		(property "Value" ""
			(at 0 0 180)
			(layer "F.Fab")
			(effects
				(font
					(size 1.27 1.27)
				)
			)
		)
		(duplicate_pad_numbers_are_jumpers no)
		(pad "BR20" smd circle
			(at -20.938998 1.643126)
			(size 0.4318 0.4318)
			(layers "F.Cu" "F.Mask" "F.Paste")
			(net "FM_MODPRST_HFI0_CPU0_LVT2_N")
		)
		(pad "BR22" smd circle
			(at -19.221958 1.643126)
			(size 0.4318 0.4318)
			(layers "F.Cu" "F.Mask" "F.Paste")
			(net "PVCCMCP_CPU0")
		)
		(pad "BR24" smd circle
			(at -17.504918 1.643126)
			(size 0.4318 0.4318)
			(layers "F.Cu" "F.Mask" "F.Paste")
			(net "PVCCMCP_CPU0")
		)
		(pad "BR26" smd circle
			(at -15.787878 1.643126)
			(size 0.4318 0.4318)
			(layers "F.Cu" "F.Mask" "F.Paste")
			(net "GND")
		)
		(pad "BR60" smd circle
			(at 14.929612 -0.156972)
			(size 0.508 0.508)
			(layers "F.Cu" "F.Mask" "F.Paste")
			(net "PVCCIN_CPU0")
		)
		(pad "BR62" smd circle
			(at 16.646398 -0.156972)
			(size 0.4318 0.4318)
			(layers "F.Cu" "F.Mask" "F.Paste")
			(net "PVCCIN_CPU0")
		)
		(pad "BR64" smd circle
			(at 18.363438 -0.156972)
			(size 0.4318 0.4318)
			(layers "F.Cu" "F.Mask" "F.Paste")
			(net "GND")
		)
		(pad "BR66" smd circle
			(at 20.080478 -0.156972)
			(size 0.4318 0.4318)
			(layers "F.Cu" "F.Mask" "F.Paste")
			(net "GND")
		)
		(pad "BR68" smd circle
			(at 21.797518 -0.156972)
			(size 0.4318 0.4318)
			(layers "F.Cu" "F.Mask" "F.Paste")
			(net "GND")
		)
		(pad "BR70" smd circle
			(at 23.514558 -0.156972)
			(size 0.4318 0.4318)
			(layers "F.Cu" "F.Mask" "F.Paste")
			(net "GND")
		)
		(pad "BR72" smd circle
			(at 25.231598 -0.156972)
			(size 0.4318 0.4318)
			(layers "F.Cu" "F.Mask" "F.Paste")
			(net "GND")
		)
		(pad "BR74" smd circle
			(at 26.948384 -0.156972)
			(size 0.4318 0.4318)
			(layers "F.Cu" "F.Mask" "F.Paste")
			(net "GND")
		)
		(pad "BR76" smd circle
			(at 28.665424 -0.156972)
			(size 0.4318 0.4318)
			(layers "F.Cu" "F.Mask" "F.Paste")
			(net "GND")
		)
		(pad "BR78" smd circle
			(at 30.382464 -0.156972)
			(size 0.4318 0.4318)
			(layers "F.Cu" "F.Mask" "F.Paste")
			(net "GND")
		)
		(pad "BR80" smd circle
			(at 32.099504 -0.156972)
			(size 0.4318 0.4318)
			(layers "F.Cu" "F.Mask" "F.Paste")
			(net "GND")
		)
		(pad "BR82" smd circle
			(at 33.816544 -0.156972)
			(size 0.4318 0.4318)
			(layers "F.Cu" "F.Mask" "F.Paste")
			(net "GND")
		)
		(pad "BR84" smd custom
			(at 35.533584 -0.156972 270)
			(size 0.10795 0.10795)
			(layers "F.Cu" "F.Mask" "F.Paste")
			(net "PVCCIN_CPU0")
			(options
				(clearance outline)
				(anchor circle)
			)
			(primitives
				(gr_poly
					(pts
						(arc
							(start 0.2159 -0.0381)
							(mid 0 -0.254)
							(end -0.2159 -0.0381)
						)
						(arc
							(start -0.2159 0.0381)
							(mid 0 0.254)
							(end 0.2159 0.0381)
						)
					)
					(width 0)
					(fill yes)
				)
			)
		)
		(pad "BT3" smd custom
			(at -35.533584 2.138426 90)
			(size 0.10795 0.10795)
			(layers "F.Cu" "F.Mask" "F.Paste")
			(net "GND")
			(options
				(clearance outline)
				(anchor circle)
			)
			(primitives
				(gr_poly
					(pts
						(arc
							(start 0.2159 -0.0381)
							(mid 0 -0.254)
							(end -0.2159 -0.0381)
						)
						(arc
							(start -0.2159 0.0381)
							(mid 0 0.254)
							(end 0.2159 0.0381)
						)
					)
					(width 0)
					(fill yes)
				)
			)
		)
		(pad "BT5" smd circle
			(at -33.816544 2.138426)
			(size 0.4318 0.4318)
			(layers "F.Cu" "F.Mask" "F.Paste")
			(net "GND")
		)
		(pad "BT7" smd circle
			(at -32.099504 2.138426)
			(size 0.4318 0.4318)
			(layers "F.Cu" "F.Mask" "F.Paste")
			(net "P3E_CPU0_PE2_SS_RXN<11>")
		)
		(pad "BT9" smd circle
			(at -30.382464 2.138426)
			(size 0.4318 0.4318)
			(layers "F.Cu" "F.Mask" "F.Paste")
			(net "GND")
		)
		(pad "BT11" smd circle
			(at -28.665424 2.138426)
			(size 0.4318 0.4318)
			(layers "F.Cu" "F.Mask" "F.Paste")
			(net "PVCCIOMCP_CPU0")
		)
		(pad "BT13" smd circle
			(at -26.948384 2.138426)
			(size 0.4318 0.4318)
			(layers "F.Cu" "F.Mask" "F.Paste")
			(net "PVCCIOMCP_CPU0")
		)
		(pad "BT15" smd circle
			(at -25.231598 2.138426)
			(size 0.4318 0.4318)
			(layers "F.Cu" "F.Mask" "F.Paste")
			(net "PVCCIOMCP_CPU0")
		)
		(pad "BT17" smd circle
			(at -23.514558 2.138426)
			(size 0.4318 0.4318)
			(layers "F.Cu" "F.Mask" "F.Paste")
			(net "VSENSE_PVCCIOMCP_CPU0_SKT_VSEN")
		)
		(pad "BT19" smd circle
			(at -21.797518 2.138426)
			(size 0.4318 0.4318)
			(layers "F.Cu" "F.Mask" "F.Paste")
			(net "FM_MODPRST_HFI1_CPU0_LVT2_N")
		)
		(pad "BT21" smd circle
			(at -20.080478 2.138426)
			(size 0.4318 0.4318)
			(layers "F.Cu" "F.Mask" "F.Paste")
			(net "GND")
		)
		(pad "BT23" smd circle
			(at -18.363438 2.138426)
			(size 0.4318 0.4318)
			(layers "F.Cu" "F.Mask" "F.Paste")
			(net "GND")
		)
		(pad "BT25" smd circle
			(at -16.646398 2.138426)
			(size 0.4318 0.4318)
			(layers "F.Cu" "F.Mask" "F.Paste")
			(net "GND")
		)
		(pad "BT27" smd circle
			(at -14.929612 2.138426)
			(size 0.4318 0.4318)
			(layers "F.Cu" "F.Mask" "F.Paste")
			(net "P1V8_MCP_CPU0")
		)
		(pad "BT61" smd circle
			(at 15.787878 0.338074)
			(size 0.4318 0.4318)
			(layers "F.Cu" "F.Mask" "F.Paste")
			(net "PVCCIN_CPU0")
		)
		(pad "BT63" smd circle
			(at 17.504918 0.338074)
			(size 0.4318 0.4318)
			(layers "F.Cu" "F.Mask" "F.Paste")
			(net "PVCCIN_CPU0")
		)
		(pad "BT65" smd circle
			(at 19.221958 0.338074)
			(size 0.4318 0.4318)
			(layers "F.Cu" "F.Mask" "F.Paste")
			(net "PVCCIN_CPU0")
		)
		(pad "BT67" smd circle
			(at 20.938998 0.338074)
			(size 0.4318 0.4318)
			(layers "F.Cu" "F.Mask" "F.Paste")
			(net "PVCCIN_CPU0")
		)
		(pad "BT69" smd circle
			(at 22.656038 0.338074)
			(size 0.4318 0.4318)
			(layers "F.Cu" "F.Mask" "F.Paste")
			(net "PVCCIN_CPU0")
		)
		(pad "BT71" smd circle
			(at 24.373078 0.338074)
			(size 0.4318 0.4318)
			(layers "F.Cu" "F.Mask" "F.Paste")
			(net "PVCCIN_CPU0")
		)
		(pad "BT73" smd circle
			(at 26.090118 0.338074)
			(size 0.4318 0.4318)
			(layers "F.Cu" "F.Mask" "F.Paste")
			(net "PVCCIN_CPU0")
		)
		(pad "BT75" smd circle
			(at 27.806904 0.338074)
			(size 0.4318 0.4318)
			(layers "F.Cu" "F.Mask" "F.Paste")
			(net "PVCCIN_CPU0")
		)
		(pad "BT77" smd circle
			(at 29.523944 0.338074)
			(size 0.4318 0.4318)
			(layers "F.Cu" "F.Mask" "F.Paste")
			(net "PVCCIN_CPU0")
		)
		(pad "BT79" smd circle
			(at 31.240984 0.338074)
			(size 0.4318 0.4318)
			(layers "F.Cu" "F.Mask" "F.Paste")
			(net "PVCCIN_CPU0")
		)
		(pad "BT81" smd circle
			(at 32.958024 0.338074)
			(size 0.4318 0.4318)
			(layers "F.Cu" "F.Mask" "F.Paste")
			(net "PVCCIN_CPU0")
		)
		(pad "BT83" smd circle
			(at 34.675064 0.338074)
			(size 0.4318 0.4318)
			(layers "F.Cu" "F.Mask" "F.Paste")
			(net "PVCCIN_CPU0")
		)
		(pad "BU4" smd circle
			(at -34.675064 2.633726)
			(size 0.4318 0.4318)
			(layers "F.Cu" "F.Mask" "F.Paste")
			(net "P3E_CPU0_PE2_SS_TXN<12>")
		)
		(pad "BU6" smd circle
			(at -32.958024 2.633726)
			(size 0.4318 0.4318)
			(layers "F.Cu" "F.Mask" "F.Paste")
			(net "P3E_CPU0_PE2_SS_RXP<10>")
		)
		(pad "BU8" smd circle
			(at -31.240984 2.633726)
			(size 0.4318 0.4318)
			(layers "F.Cu" "F.Mask" "F.Paste")
			(net "GND")
		)
		(pad "BU10" smd circle
			(at -29.523944 2.633726)
			(size 0.4318 0.4318)
			(layers "F.Cu" "F.Mask" "F.Paste")
			(net "GND")
		)
		(pad "BU12" smd circle
			(at -27.806904 2.633726)
			(size 0.4318 0.4318)
			(layers "F.Cu" "F.Mask" "F.Paste")
			(net "PVCCIOMCP_CPU0")
		)
		(pad "BU14" smd circle
			(at -26.090118 2.633726)
			(size 0.4318 0.4318)
			(layers "F.Cu" "F.Mask" "F.Paste")
			(net "PVCCIOMCP_CPU0")
		)
		(pad "BU16" smd circle
			(at -24.373078 2.633726)
			(size 0.4318 0.4318)
			(layers "F.Cu" "F.Mask" "F.Paste")
			(net "VSENSE_PVCCIOMCP_CPU0_SKT_VRTN")
		)
		(pad "BU18" smd circle
			(at -22.656038 2.633726)
			(size 0.4318 0.4318)
			(layers "F.Cu" "F.Mask" "F.Paste")
			(net "PVCCIOMCP_CPU0")
		)
		(pad "BU20" smd circle
			(at -20.938998 2.633726)
			(size 0.4318 0.4318)
			(layers "F.Cu" "F.Mask" "F.Paste")
			(net "PVCCMCP_CPU0")
		)
		(pad "BU22" smd circle
			(at -19.221958 2.633726)
			(size 0.4318 0.4318)
			(layers "F.Cu" "F.Mask" "F.Paste")
			(net "PVCCMCP_CPU0")
		)
		(pad "BU24" smd circle
			(at -17.504918 2.633726)
			(size 0.4318 0.4318)
			(layers "F.Cu" "F.Mask" "F.Paste")
			(net "CLK_100M_CPU0_PE_REFCLK_DN")
		)
		(pad "BU26" smd circle
			(at -15.787878 2.633726)
			(size 0.4318 0.4318)
			(layers "F.Cu" "F.Mask" "F.Paste")
			(net "P1V8_MCP_CPU0")
		)
		(pad "BU60" smd circle
			(at 14.929612 0.833628)
			(size 0.508 0.508)
			(layers "F.Cu" "F.Mask" "F.Paste")
			(net "PVCCIN_CPU0")
		)
		(pad "BU62" smd circle
			(at 16.646398 0.833628)
			(size 0.4318 0.4318)
			(layers "F.Cu" "F.Mask" "F.Paste")
			(net "PVCCIN_CPU0")
		)
		(pad "BU64" smd circle
			(at 18.363438 0.833628)
			(size 0.4318 0.4318)
			(layers "F.Cu" "F.Mask" "F.Paste")
			(net "PVCCIN_CPU0")
		)
		(pad "BU66" smd circle
			(at 20.080478 0.833628)
			(size 0.4318 0.4318)
			(layers "F.Cu" "F.Mask" "F.Paste")
			(net "PVCCIN_CPU0")
		)
		(pad "BU68" smd circle
			(at 21.797518 0.833628)
			(size 0.4318 0.4318)
			(layers "F.Cu" "F.Mask" "F.Paste")
			(net "PVCCIN_CPU0")
		)
		(pad "BU70" smd circle
			(at 23.514558 0.833628)
			(size 0.4318 0.4318)
			(layers "F.Cu" "F.Mask" "F.Paste")
			(net "PVCCIN_CPU0")
		)
		(pad "BU72" smd circle
			(at 25.231598 0.833628)
			(size 0.4318 0.4318)
			(layers "F.Cu" "F.Mask" "F.Paste")
			(net "PVCCIN_CPU0")
		)
		(pad "BU74" smd circle
			(at 26.948384 0.833628)
			(size 0.4318 0.4318)
			(layers "F.Cu" "F.Mask" "F.Paste")
			(net "PVCCIN_CPU0")
		)
		(pad "BU76" smd circle
			(at 28.665424 0.833628)
			(size 0.4318 0.4318)
			(layers "F.Cu" "F.Mask" "F.Paste")
			(net "PVCCIN_CPU0")
		)
		(pad "BU78" smd circle
			(at 30.382464 0.833628)
			(size 0.4318 0.4318)
			(layers "F.Cu" "F.Mask" "F.Paste")
			(net "PVCCIN_CPU0")
		)
		(pad "BU80" smd circle
			(at 32.099504 0.833628)
			(size 0.4318 0.4318)
			(layers "F.Cu" "F.Mask" "F.Paste")
			(net "PVCCIN_CPU0")
		)
		(pad "BU82" smd circle
			(at 33.816544 0.833628)
			(size 0.4318 0.4318)
			(layers "F.Cu" "F.Mask" "F.Paste")
			(net "PVCCIN_CPU0")
		)
		(pad "BU84" smd custom
			(at 35.533584 0.833628 270)
			(size 0.10795 0.10795)
			(layers "F.Cu" "F.Mask" "F.Paste")
			(net "PVCCIN_CPU0")
			(options
				(clearance outline)
				(anchor circle)
			)
			(primitives
				(gr_poly
					(pts
						(arc
							(start 0.2159 -0.0381)
							(mid 0 -0.254)
							(end -0.2159 -0.0381)
						)
						(arc
							(start -0.2159 0.0381)
							(mid 0 0.254)
							(end 0.2159 0.0381)
						)
					)
					(width 0)
					(fill yes)
				)
			)
		)
		(pad "BV3" smd custom
			(at -35.533584 3.128772 90)
			(size 0.10795 0.10795)
			(layers "F.Cu" "F.Mask" "F.Paste")
			(net "P3E_CPU0_PE2_SS_TXP<11>")
			(options
				(clearance outline)
				(anchor circle)
			)
			(primitives
				(gr_poly
					(pts
						(arc
							(start 0.2159 -0.0381)
							(mid 0 -0.254)
							(end -0.2159 -0.0381)
						)
						(arc
							(start -0.2159 0.0381)
							(mid 0 0.254)
							(end 0.2159 0.0381)
						)
					)
					(width 0)
					(fill yes)
				)
			)
		)
		(pad "BV5" smd circle
			(at -33.816544 3.128772)
			(size 0.4318 0.4318)
			(layers "F.Cu" "F.Mask" "F.Paste")
			(net "GND")
		)
		(pad "BV7" smd circle
			(at -32.099504 3.128772)
			(size 0.4318 0.4318)
			(layers "F.Cu" "F.Mask" "F.Paste")
			(net "P3E_CPU0_PE2_SS_RXN<10>")
		)
		(pad "BV9" smd circle
			(at -30.382464 3.128772)
			(size 0.4318 0.4318)
			(layers "F.Cu" "F.Mask" "F.Paste")
			(net "P3E_CPU0_PE2_SS_RXP<8>")
		)
		(pad "BV11" smd circle
			(at -28.665424 3.128772)
			(size 0.4318 0.4318)
			(layers "F.Cu" "F.Mask" "F.Paste")
			(net "PVCCIOMCP_CPU0")
		)
		(pad "BV13" smd circle
			(at -26.948384 3.128772)
			(size 0.4318 0.4318)
			(layers "F.Cu" "F.Mask" "F.Paste")
			(net "PVCCIOMCP_CPU0")
		)
		(pad "BV15" smd circle
			(at -25.231598 3.128772)
			(size 0.4318 0.4318)
			(layers "F.Cu" "F.Mask" "F.Paste")
			(net "PVCCIOMCP_CPU0")
		)
		(pad "BV17" smd circle
			(at -23.514558 3.128772)
			(size 0.4318 0.4318)
			(layers "F.Cu" "F.Mask" "F.Paste")
			(net "GND")
		)
		(pad "BV19" smd circle
			(at -21.797518 3.128772)
			(size 0.4318 0.4318)
			(layers "F.Cu" "F.Mask" "F.Paste")
			(net "PVCCMCP_CPU0")
		)
		(pad "BV21" smd circle
			(at -20.080478 3.128772)
			(size 0.4318 0.4318)
			(layers "F.Cu" "F.Mask" "F.Paste")
			(net "PVCCMCP_CPU0")
		)
		(pad "BV23" smd circle
			(at -18.363438 3.128772)
			(size 0.4318 0.4318)
			(layers "F.Cu" "F.Mask" "F.Paste")
			(net "TP_CPU0_RSVD_124")
		)
		(pad "BV25" smd circle
			(at -16.646398 3.128772)
			(size 0.4318 0.4318)
			(layers "F.Cu" "F.Mask" "F.Paste")
			(net "GND")
		)
		(pad "BV27" smd circle
			(at -14.929612 3.128772)
			(size 0.4318 0.4318)
			(layers "F.Cu" "F.Mask" "F.Paste")
			(net "P1V8_MCP_CPU0")
		)
		(pad "BV61" smd circle
			(at 15.787878 1.328674)
			(size 0.4318 0.4318)
			(layers "F.Cu" "F.Mask" "F.Paste")
			(net "PVCCIN_CPU0")
		)
		(pad "BV63" smd circle
			(at 17.504918 1.328674)
			(size 0.4318 0.4318)
			(layers "F.Cu" "F.Mask" "F.Paste")
			(net "PVCCIN_CPU0")
		)
		(pad "BV65" smd circle
			(at 19.221958 1.328674)
			(size 0.4318 0.4318)
			(layers "F.Cu" "F.Mask" "F.Paste")
			(net "PVCCIN_CPU0")
		)
		(pad "BV67" smd circle
			(at 20.938998 1.328674)
			(size 0.4318 0.4318)
			(layers "F.Cu" "F.Mask" "F.Paste")
			(net "PVCCIN_CPU0")
		)
		(pad "BV69" smd circle
			(at 22.656038 1.328674)
			(size 0.4318 0.4318)
			(layers "F.Cu" "F.Mask" "F.Paste")
			(net "PVCCIN_CPU0")
		)
		(pad "BV71" smd circle
			(at 24.373078 1.328674)
			(size 0.4318 0.4318)
			(layers "F.Cu" "F.Mask" "F.Paste")
			(net "PVCCIN_CPU0")
		)
		(pad "BV73" smd circle
			(at 26.090118 1.328674)
			(size 0.4318 0.4318)
			(layers "F.Cu" "F.Mask" "F.Paste")
			(net "PVCCIN_CPU0")
		)
		(pad "BV75" smd circle
			(at 27.806904 1.328674)
			(size 0.4318 0.4318)
			(layers "F.Cu" "F.Mask" "F.Paste")
			(net "PVCCIN_CPU0")
		)
		(pad "BV77" smd circle
			(at 29.523944 1.328674)
			(size 0.4318 0.4318)
			(layers "F.Cu" "F.Mask" "F.Paste")
			(net "PVCCIN_CPU0")
		)
		(pad "BV79" smd circle
			(at 31.240984 1.328674)
			(size 0.4318 0.4318)
			(layers "F.Cu" "F.Mask" "F.Paste")
			(net "PVCCIN_CPU0")
		)
		(pad "BV81" smd circle
			(at 32.958024 1.328674)
			(size 0.4318 0.4318)
			(layers "F.Cu" "F.Mask" "F.Paste")
			(net "PVCCIN_CPU0")
		)
		(pad "BV83" smd circle
			(at 34.675064 1.328674)
			(size 0.4318 0.4318)
			(layers "F.Cu" "F.Mask" "F.Paste")
			(net "PVCCIN_CPU0")
		)
		(pad "BW4" smd circle
			(at -34.675064 3.624326)
			(size 0.4318 0.4318)
			(layers "F.Cu" "F.Mask" "F.Paste")
			(net "P3E_CPU0_PE2_SS_TXN<11>")
		)
		(pad "BW6" smd circle
			(at -32.958024 3.624326)
			(size 0.4318 0.4318)
			(layers "F.Cu" "F.Mask" "F.Paste")
			(net "GND")
		)
		(pad "BW8" smd circle
			(at -31.240984 3.624326)
			(size 0.4318 0.4318)
			(layers "F.Cu" "F.Mask" "F.Paste")
			(net "P3E_CPU0_PE2_SS_RXP<9>")
		)
		(pad "BW10" smd circle
			(at -29.523944 3.624326)
			(size 0.4318 0.4318)
			(layers "F.Cu" "F.Mask" "F.Paste")
			(net "TP_CPU0_RSVD_123")
		)
		(pad "BW12" smd circle
			(at -27.806904 3.624326)
			(size 0.4318 0.4318)
			(layers "F.Cu" "F.Mask" "F.Paste")
			(net "GND")
		)
		(pad "BW14" smd circle
			(at -26.090118 3.624326)
			(size 0.4318 0.4318)
			(layers "F.Cu" "F.Mask" "F.Paste")
			(net "GND")
		)
		(pad "BW16" smd circle
			(at -24.373078 3.624326)
			(size 0.4318 0.4318)
			(layers "F.Cu" "F.Mask" "F.Paste")
			(net "GND")
		)
		(pad "BW18" smd circle
			(at -22.656038 3.624326)
			(size 0.4318 0.4318)
			(layers "F.Cu" "F.Mask" "F.Paste")
			(net "GND")
		)
		(pad "BW20" smd circle
			(at -20.938998 3.624326)
			(size 0.4318 0.4318)
			(layers "F.Cu" "F.Mask" "F.Paste")
			(net "PVCCMCP_CPU0")
		)
		(pad "BW22" smd circle
			(at -19.221958 3.624326)
			(size 0.4318 0.4318)
			(layers "F.Cu" "F.Mask" "F.Paste")
			(net "TP_CPU0_RSVD_121")
		)
		(pad "BW24" smd circle
			(at -17.504918 3.624326)
			(size 0.4318 0.4318)
			(layers "F.Cu" "F.Mask" "F.Paste")
			(net "CLK_100M_CPU0_PE_REFCLK_DP")
		)
		(pad "BW26" smd circle
			(at -15.787878 3.624326)
			(size 0.4318 0.4318)
			(layers "F.Cu" "F.Mask" "F.Paste")
			(net "GND")
		)
		(pad "BW60" smd circle
			(at 14.929612 1.824228)
			(size 0.508 0.508)
			(layers "F.Cu" "F.Mask" "F.Paste")
			(net "PVCCIN_CPU0")
		)
		(pad "BW62" smd circle
			(at 16.646398 1.824228)
			(size 0.4318 0.4318)
			(layers "F.Cu" "F.Mask" "F.Paste")
			(net "PVCCIN_CPU0")
		)
		(pad "BW64" smd circle
			(at 18.363438 1.824228)
			(size 0.4318 0.4318)
			(layers "F.Cu" "F.Mask" "F.Paste")
			(net "PVCCIN_CPU0")
		)
	)
)
